# TIMECARD (Time Appliance Project (Time Card)) — schematic netlist excerpt (pin names and nets, part order shuffled) for the footprints in the layout excerpt that follows; sources: Cadence DE-HDL packaged netlist, KiCad conversion of R4006-B0001-02_R01.brd

R33  RESISTOR  2.2OHM 1%  pkg SMC_0805R_H026  page 32 : \1\ = UNNAMED_516_CAPACITOR_I37_2 ; \2\ = SG
L14  FERRITEBEAD  600OHM 25%  pkg SMC_0603R_H037  page 15 : \1\ = VDD3V3_OSC_200M ; \2\ = XP3R3V

(kicad_pcb
	(version 20260206)
	(generator "pcbnew")
	(generator_version "10.0")
	(general
		(thickness 1.6)
		(legacy_teardrops no)
	)
	(paper "A4")
	(title_block
		(title "timecard-production-celestica-r4006 — R4006-B0001-02_R01.brd")
		(comment 1 "Time Appliance Project (Time Card) / footprints 1079-1080 of 1113")
	)
	(layers
		(0 "F.Cu" signal "TOP")
		(4 "In1.Cu" signal "L02_GND1")
		(6 "In2.Cu" signal "L03_SIG1")
		(8 "In3.Cu" signal "L04_GND2")
		(10 "In4.Cu" signal "L05_VCC1")
		(12 "In5.Cu" signal "L06_VCC2")
		(14 "In6.Cu" signal "L07_GND3")
		(16 "In7.Cu" signal "L08_SIG2")
		(18 "In8.Cu" signal "L09_GND4")
		(2 "B.Cu" signal "BOTTOM")
		(9 "F.Adhes" user "F.Adhesive")
		(11 "B.Adhes" user "B.Adhesive")
		(13 "F.Paste" user "Package Geometry/Pastemask Top")
		(15 "B.Paste" user "Package Geometry/Pastemask Bottom")
		(5 "F.SilkS" user "Ref Des/Silkscreen Top")
		(7 "B.SilkS" user "Ref Des/Silkscreen Bottom")
		(1 "F.Mask" user "Board Geometry/Soldermask Top")
		(3 "B.Mask" user "Board Geometry/Soldermask Bottom")
		(17 "Dwgs.User" user "User.Drawings")
		(19 "Cmts.User" user "User.Comments")
		(21 "Eco1.User" user "User.Eco1")
		(23 "Eco2.User" user "User.Eco2")
		(25 "Edge.Cuts" user "Board Geometry/Outline")
		(27 "Margin" user)
		(31 "F.CrtYd" user "Package Geometry/Place Bound Top")
		(29 "B.CrtYd" user "Package Geometry/Place Bound Bottom")
		(35 "F.Fab" user "Ref Des/Assembly Top")
		(33 "B.Fab" user "Ref Des/Assembly Bottom")
	)
	(footprint ""
		(layer "B.Cu")
		(at 108.458 -20.447 90)
		(property "Reference" "L14"
			(at 0.635 1.48463 270)
			(unlocked yes)
			(layer "B.SilkS")
			(effects
				(font
					(size 0.7874 0.5842)
					(thickness 0.1524)
				)
				(justify mirror)
			)
		)
		(property "Value" "VAL*"
			(at -0.014732 2.526538 90)
			(unlocked yes)
			(layer "B.Fab")
			(hide yes)
			(effects
				(font
					(size 0.7874 0.5842)
					(thickness 0.000001)
				)
				(justify mirror)
			)
		)
		(property "Tolerance" "TOL*"
			(at -0.014732 3.503676 90)
			(unlocked yes)
			(layer "Cmts.User")
			(hide yes)
			(effects
				(font
					(size 0.7874 0.5842)
					(thickness 0.000001)
				)
				(justify mirror)
			)
		)
		(property "User Part Number" "PARTNUM*"
			(at -0.02794 4.480814 90)
			(unlocked yes)
			(layer "Cmts.User")
			(hide yes)
			(effects
				(font
					(size 0.7874 0.5842)
					(thickness 0.000001)
				)
				(justify mirror)
			)
		)
		(property "Device Type" "FERRITEBEAD-G191-10097-01,600OA"
			(at -0.014732 1.600708 90)
			(unlocked yes)
			(layer "B.Fab")
			(hide yes)
			(effects
				(font
					(size 0.7874 0.5842)
					(thickness 0.000001)
				)
				(justify mirror)
			)
		)
		(duplicate_pad_numbers_are_jumpers no)
		(fp_line
			(start 1.3208 -0.7112)
			(end -1.3208 -0.7112)
			(stroke
				(width 0.1)
				(type default)
			)
			(layer "B.SilkS")
		)
		(fp_line
			(start -1.3208 -0.7112)
			(end -1.3208 0.7112)
			(stroke
				(width 0.1)
				(type default)
			)
			(layer "B.SilkS")
		)
		(fp_line
			(start 1.3208 0.7112)
			(end 1.3208 -0.7112)
			(stroke
				(width 0.1)
				(type default)
			)
			(layer "B.SilkS")
		)
		(fp_line
			(start -1.3208 0.7112)
			(end 1.3208 0.7112)
			(stroke
				(width 0.1)
				(type default)
			)
			(layer "B.SilkS")
		)
		(fp_rect
			(start 1.3208 0.7112)
			(end -1.3208 -0.7112)
			(stroke
				(width 0)
				(type default)
			)
			(fill no)
			(layer "B.CrtYd")
		)
		(fp_line
			(start 0.8128 -0.4572)
			(end -0.8128 -0.4572)
			(stroke
				(width 0.1)
				(type default)
			)
			(layer "B.Fab")
		)
		(fp_line
			(start -0.8128 -0.4572)
			(end -0.8128 0.4572)
			(stroke
				(width 0.1)
				(type default)
			)
			(layer "B.Fab")
		)
		(fp_line
			(start 0.8128 0.4572)
			(end 0.8128 -0.4572)
			(stroke
				(width 0.1)
				(type default)
			)
			(layer "B.Fab")
		)
		(fp_line
			(start -0.8128 0.4572)
			(end 0.8128 0.4572)
			(stroke
				(width 0.1)
				(type default)
			)
			(layer "B.Fab")
		)
		(pad "1" smd rect
			(at 0.6858 0 270)
			(size 0.762 0.8636)
			(layers "B.Cu" "B.Mask" "B.Paste")
			(net "VDD3V3_OSC_200M")
		)
		(pad "2" smd rect
			(at -0.6858 0 270)
			(size 0.762 0.8636)
			(layers "B.Cu" "B.Mask" "B.Paste")
			(net "XP3R3V")
		)
		(zone
			(layer "B.Cu")
			(hatch none 0.5)
			(connect_pads
				(clearance 0)
			)
			(min_thickness 0.25)
			(keepout
				(tracks allowed)
				(vias not_allowed)
				(pads allowed)
				(copperpour not_allowed)
				(footprints allowed)
			)
			(placement
				(enabled no)
				(sheetname "")
			)
			(fill
				(thermal_gap 0.5)
				(thermal_bridge_width 0.5)
				(island_removal_mode 0)
			)
			(polygon
				(pts
					(xy 108.9152 -20.5994) (xy 108.0008 -20.5994) (xy 108.0008 -20.2946) (xy 108.9152 -20.2946)
				)
			)
		)
		(zone
			(layer "B.Cu")
			(hatch none 0.5)
			(connect_pads
				(clearance 0)
			)
			(min_thickness 0.25)
			(keepout
				(tracks not_allowed)
				(vias allowed)
				(pads allowed)
				(copperpour not_allowed)
				(footprints allowed)
			)
			(placement
				(enabled no)
				(sheetname "")
			)
			(fill
				(thermal_gap 0.5)
				(thermal_bridge_width 0.5)
				(island_removal_mode 0)
			)
			(polygon
				(pts
					(xy 108.9152 -20.5994) (xy 108.0008 -20.5994) (xy 108.0008 -20.2946) (xy 108.9152 -20.2946)
				)
			)
		)
	)
	(footprint ""
		(layer "B.Cu")
		(at 46.736 -104.902 180)
		(property "Reference" "R33"
			(at 0.1778 1.61163 0)
			(unlocked yes)
			(layer "B.SilkS")
			(effects
				(font
					(size 0.7874 0.5842)
					(thickness 0.1524)
				)
				(justify mirror)
			)
		)
		(property "Value" "VAL*"
			(at -0.0508 3.159506 180)
			(unlocked yes)
			(layer "B.Fab")
			(hide yes)
			(effects
				(font
					(size 0.7874 0.5842)
					(thickness 0.1524)
				)
				(justify mirror)
			)
		)
		(property "Tolerance" "TOL*"
			(at -0.0508 4.124706 180)
			(unlocked yes)
			(layer "Cmts.User")
			(hide yes)
			(effects
				(font
					(size 0.7874 0.5842)
					(thickness 0.1524)
				)
				(justify mirror)
			)
		)
		(property "User Part Number" "PARTNUM*"
			(at -0.0508 5.089906 180)
			(unlocked yes)
			(layer "Cmts.User")
			(hide yes)
			(effects
				(font
					(size 0.7874 0.5842)
					(thickness 0.1524)
				)
				(justify mirror)
			)
		)
		(property "Device Type" "RESISTOR-G157-12R20-01,2.2OHM,A"
			(at 0 2.194306 180)
			(unlocked yes)
			(layer "B.Fab")
			(hide yes)
			(effects
				(font
					(size 0.7874 0.5842)
					(thickness 0.1524)
				)
				(justify mirror)
			)
		)
		(duplicate_pad_numbers_are_jumpers no)
		(fp_line
			(start 1.5748 0.9398)
			(end -1.5748 0.9398)
			(stroke
				(width 0.1)
				(type default)
			)
			(layer "B.SilkS")
		)
		(fp_line
			(start 1.5748 -0.9398)
			(end 1.5748 0.9398)
			(stroke
				(width 0.1)
				(type default)
			)
			(layer "B.SilkS")
		)
		(fp_line
			(start -1.5748 0.9398)
			(end -1.5748 -0.9398)
			(stroke
				(width 0.1)
				(type default)
			)
			(layer "B.SilkS")
		)
		(fp_line
			(start -1.5748 -0.9398)
			(end 1.5748 -0.9398)
			(stroke
				(width 0.1)
				(type default)
			)
			(layer "B.SilkS")
		)
		(fp_rect
			(start -1.5748 0.9398)
			(end 1.5748 -0.9398)
			(stroke
				(width 0)
				(type default)
			)
			(fill no)
			(layer "B.CrtYd")
		)
		(fp_line
			(start 1.016 0.635)
			(end -1.016 0.635)
			(stroke
				(width 0.1)
				(type default)
			)
			(layer "B.Fab")
		)
		(fp_line
			(start 1.016 -0.635)
			(end 1.016 0.635)
			(stroke
				(width 0.1)
				(type default)
			)
			(layer "B.Fab")
		)
		(fp_line
			(start -1.016 0.635)
			(end -1.016 -0.635)
			(stroke
				(width 0.1)
				(type default)
			)
			(layer "B.Fab")
		)
		(fp_line
			(start -1.016 -0.635)
			(end 1.016 -0.635)
			(stroke
				(width 0.1)
				(type default)
			)
			(layer "B.Fab")
		)
		(pad "1" smd rect
			(at 0.8382 0)
			(size 0.9652 1.3716)
			(layers "B.Cu" "B.Mask" "B.Paste")
			(net "UNNAMED_516_CAPACITOR_I37_2")
		)
		(pad "2" smd rect
			(at -0.8382 0)
			(size 0.9652 1.3716)
			(layers "B.Cu" "B.Mask" "B.Paste")
			(net "SG")
		)
		(zone
			(layer "B.Cu")
			(hatch none 0.5)
			(connect_pads
				(clearance 0)
			)
			(min_thickness 0.25)
			(keepout
				(tracks allowed)
				(vias not_allowed)
				(pads allowed)
				(copperpour not_allowed)
				(footprints allowed)
			)
			(placement
				(enabled no)
				(sheetname "")
			)
			(fill
				(thermal_gap 0.5)
				(thermal_bridge_width 0.5)
				(island_removal_mode 0)
			)
			(polygon
				(pts
					(xy 46.9646 -105.537) (xy 46.5074 -105.537) (xy 46.5074 -104.267) (xy 46.9646 -104.267)
				)
			)
		)
	)
)
